(kicad_pcb
	(version 20260206)
	(generator "pcbnew")
	(generator_version "10.0")
	(general
		(thickness 1.6)
		(legacy_teardrops no)
	)
	(paper "A4")
	(title_block
		(title "03242023_DA0F0TMBIJ0_F0T_Motherboard_J_brd_V01_OCP.brd")
		(comment 1 "Grand Teton / footprints 3745-3749 of 6105")
	)
	(layers
		(0 "F.Cu" signal "TOP")
		(4 "In1.Cu" signal "GND")
		(6 "In2.Cu" signal "IN1")
		(8 "In3.Cu" signal "GND1")
		(10 "In4.Cu" signal "IN2")
		(12 "In5.Cu" signal "GND2")
		(14 "In6.Cu" signal "IN3")
		(16 "In7.Cu" signal "GND3")
		(18 "In8.Cu" signal "VCC")
		(20 "In9.Cu" signal "VCC1")
		(22 "In10.Cu" signal "GND4")
		(24 "In11.Cu" signal "IN4")
		(26 "In12.Cu" signal "GND5")
		(28 "In13.Cu" signal "IN5")
		(30 "In14.Cu" signal "GND6")
		(32 "In15.Cu" signal "IN6")
		(34 "In16.Cu" signal "GND7")
		(2 "B.Cu" signal "BOTTOM")
		(9 "F.Adhes" user "F.Adhesive")
		(11 "B.Adhes" user "B.Adhesive")
		(13 "F.Paste" user "Package Geometry/Pastemask Top")
		(15 "B.Paste" user "Package Geometry/Pastemask Bottom")
		(5 "F.SilkS" user "Ref Des/Silkscreen Top")
		(7 "B.SilkS" user "Ref Des/Silkscreen Bottom")
		(1 "F.Mask" user "Board Geometry/Soldermask Top")
		(3 "B.Mask" user "Board Geometry/Soldermask Bottom")
		(17 "Dwgs.User" user "User.Drawings")
		(19 "Cmts.User" user "User.Comments")
		(21 "Eco1.User" user "User.Eco1")
		(23 "Eco2.User" user "User.Eco2")
		(25 "Edge.Cuts" user "Board Geometry/Outline")
		(27 "Margin" user)
		(31 "F.CrtYd" user "Package Geometry/Place Bound Top")
		(29 "B.CrtYd" user "Package Geometry/Place Bound Bottom")
		(35 "F.Fab" user "Ref Des/Assembly Top")
		(33 "B.Fab" user "Ref Des/Assembly Bottom")
	)
	(footprint ""
		(layer "F.Cu")
		(at 77.916278 -30.112462 -90)
		(property "Reference" "PD107"
			(at 0.280924 -1.999742 0)
			(unlocked yes)
			(layer "F.SilkS")
			(effects
				(font
					(size 0.7874 0.5842)
					(thickness 0.1524)
				)
				(justify left)
			)
		)
		(property "Value" ""
			(at 0 0 270)
			(layer "F.Fab")
			(effects
				(font
					(size 1.27 1.27)
				)
			)
		)
		(duplicate_pad_numbers_are_jumpers no)
		(fp_line
			(start -2.250186 0.999998)
			(end 2.631186 0.999998)
			(stroke
				(width 0.1524)
				(type default)
			)
			(layer "F.SilkS")
		)
		(fp_line
			(start 2.631186 0.999998)
			(end 2.631186 -0.999998)
			(stroke
				(width 0.1524)
				(type default)
			)
			(layer "F.SilkS")
		)
		(fp_line
			(start -0.381 0.3302)
			(end -0.381 -0.4318)
			(stroke
				(width 0.1524)
				(type default)
			)
			(layer "F.SilkS")
		)
		(fp_line
			(start -0.381 -0.0508)
			(end -0.6604 -0.0508)
			(stroke
				(width 0.1524)
				(type default)
			)
			(layer "F.SilkS")
		)
		(fp_line
			(start 0.381 -0.0508)
			(end -0.381 0.3302)
			(stroke
				(width 0.1524)
				(type default)
			)
			(layer "F.SilkS")
		)
		(fp_line
			(start 0.381 -0.0508)
			(end 0.635 -0.0508)
			(stroke
				(width 0.1524)
				(type default)
			)
			(layer "F.SilkS")
		)
		(fp_line
			(start -0.381 -0.4318)
			(end 0.381 -0.0508)
			(stroke
				(width 0.1524)
				(type default)
			)
			(layer "F.SilkS")
		)
		(fp_line
			(start 0.381 -0.4318)
			(end 0.381 0.3302)
			(stroke
				(width 0.1524)
				(type default)
			)
			(layer "F.SilkS")
		)
		(fp_line
			(start -2.250186 -0.999998)
			(end -2.250186 0.999998)
			(stroke
				(width 0.1524)
				(type default)
			)
			(layer "F.SilkS")
		)
		(fp_line
			(start 2.631186 -0.999998)
			(end -2.250186 -0.999998)
			(stroke
				(width 0.1524)
				(type default)
			)
			(layer "F.SilkS")
		)
		(fp_rect
			(start 2.6162 1.016)
			(end 2.1844 -0.9652)
			(stroke
				(width 0)
				(type default)
			)
			(fill yes)
			(layer "F.SilkS")
		)
		(fp_line
			(start -1.450086 0.999998)
			(end 1.450086 0.999998)
			(stroke
				(width 0.1)
				(type default)
			)
			(layer "F.Fab")
		)
		(fp_line
			(start 1.450086 0.999998)
			(end 1.450086 -0.999998)
			(stroke
				(width 0.1)
				(type default)
			)
			(layer "F.Fab")
		)
		(fp_line
			(start -1.450086 -0.999998)
			(end -1.450086 0.999998)
			(stroke
				(width 0.1)
				(type default)
			)
			(layer "F.Fab")
		)
		(fp_line
			(start 1.450086 -0.999998)
			(end -1.450086 -0.999998)
			(stroke
				(width 0.1)
				(type default)
			)
			(layer "F.Fab")
		)
		(fp_text user "+"
			(at -4.134866 -0.205232 270)
			(unlocked yes)
			(layer "F.SilkS")
			(effects
				(font
					(size 1.905 1.4224)
					(thickness 0.1524)
				)
				(justify left)
			)
		)
		(fp_text user "-"
			(at 2.4384 -0.22225 270)
			(unlocked yes)
			(layer "F.SilkS")
			(effects
				(font
					(size 1.905 1.4224)
					(thickness 0.1524)
				)
				(justify left)
			)
		)
		(fp_text user "+"
			(at -3.4798 -0.22225 270)
			(unlocked yes)
			(layer "F.Fab")
			(effects
				(font
					(size 1.905 1.4224)
					(thickness 0.1524)
				)
				(justify left)
			)
		)
		(fp_text user "-"
			(at 2.4384 -0.22225 270)
			(unlocked yes)
			(layer "F.Fab")
			(effects
				(font
					(size 1.905 1.4224)
					(thickness 0.1524)
				)
				(justify left)
			)
		)
		(pad "A" smd rect
			(at -1.450086 0 270)
			(size 1.3208 1.4224)
			(layers "F.Cu" "F.Mask" "F.Paste")
			(net "GND")
		)
		(pad "C" smd rect
			(at 1.450086 0 270)
			(size 1.3208 1.4224)
			(layers "F.Cu" "F.Mask" "F.Paste")
			(net "P12V_AUX")
		)
	)
	(footprint ""
		(layer "F.Cu")
		(at 226.733608 -407.871422 180)
		(property "Reference" "PR3982"
			(at 0 0 180)
			(layer "F.SilkS")
			(hide yes)
			(effects
				(font
					(size 1.27 1.27)
				)
			)
		)
		(property "Value" ""
			(at 0 0 180)
			(layer "F.Fab")
			(effects
				(font
					(size 1.27 1.27)
				)
			)
		)
		(duplicate_pad_numbers_are_jumpers no)
		(fp_line
			(start 0.7874 0.4064)
			(end -0.7874 0.4064)
			(stroke
				(width 0.1524)
				(type default)
			)
			(layer "F.SilkS")
		)
		(fp_line
			(start 0.7874 -0.4064)
			(end 0.7874 0.4064)
			(stroke
				(width 0.1524)
				(type default)
			)
			(layer "F.SilkS")
		)
		(fp_line
			(start -0.7874 0.4064)
			(end -0.7874 -0.4064)
			(stroke
				(width 0.1524)
				(type default)
			)
			(layer "F.SilkS")
		)
		(fp_line
			(start -0.7874 -0.4064)
			(end 0.7874 -0.4064)
			(stroke
				(width 0.1524)
				(type default)
			)
			(layer "F.SilkS")
		)
		(fp_line
			(start 0.67945 0.3048)
			(end 0.120396 0.3048)
			(stroke
				(width 0.1)
				(type default)
			)
			(layer "F.Fab")
		)
		(fp_line
			(start 0.67945 -0.3048)
			(end 0.67945 0.3048)
			(stroke
				(width 0.1)
				(type default)
			)
			(layer "F.Fab")
		)
		(fp_line
			(start 0.12065 -0.2794)
			(end 0.12065 -0.3048)
			(stroke
				(width 0.1)
				(type default)
			)
			(layer "F.Fab")
		)
		(fp_line
			(start 0.12065 -0.3048)
			(end 0.67945 -0.3048)
			(stroke
				(width 0.1)
				(type default)
			)
			(layer "F.Fab")
		)
		(fp_line
			(start 0.120396 0.3048)
			(end 0.120396 0.2794)
			(stroke
				(width 0.1)
				(type default)
			)
			(layer "F.Fab")
		)
		(fp_line
			(start 0.120396 0.2794)
			(end -0.12065 0.2794)
			(stroke
				(width 0.1)
				(type default)
			)
			(layer "F.Fab")
		)
		(fp_line
			(start -0.12065 0.3048)
			(end -0.67945 0.3048)
			(stroke
				(width 0.1)
				(type default)
			)
			(layer "F.Fab")
		)
		(fp_line
			(start -0.12065 0.2794)
			(end -0.12065 0.3048)
			(stroke
				(width 0.1)
				(type default)
			)
			(layer "F.Fab")
		)
		(fp_line
			(start -0.12065 -0.2794)
			(end 0.12065 -0.2794)
			(stroke
				(width 0.1)
				(type default)
			)
			(layer "F.Fab")
		)
		(fp_line
			(start -0.12065 -0.305054)
			(end -0.12065 -0.2794)
			(stroke
				(width 0.1)
				(type default)
			)
			(layer "F.Fab")
		)
		(fp_line
			(start -0.67945 0.3048)
			(end -0.67945 -0.305054)
			(stroke
				(width 0.1)
				(type default)
			)
			(layer "F.Fab")
		)
		(fp_line
			(start -0.67945 -0.305054)
			(end -0.12065 -0.305054)
			(stroke
				(width 0.1)
				(type default)
			)
			(layer "F.Fab")
		)
		(pad "1" smd circle
			(at -0.40005 0 180)
			(size 0 0)
			(layers "F.Cu" "F.Mask" "F.Paste")
			(net "AGND_HSC")
		)
		(pad "2" smd circle
			(at 0.40005 0 180)
			(size 0 0)
			(layers "F.Cu" "F.Mask" "F.Paste")
			(net "HSC_MODE_3")
		)
	)
	(footprint ""
		(layer "F.Cu")
		(at 180.64988 -126.964948 -90)
		(property "Reference" "R271"
			(at 0 0 270)
			(layer "F.SilkS")
			(hide yes)
			(effects
				(font
					(size 1.27 1.27)
				)
			)
		)
		(property "Value" ""
			(at 0 0 270)
			(layer "F.Fab")
			(effects
				(font
					(size 1.27 1.27)
				)
			)
		)
		(duplicate_pad_numbers_are_jumpers no)
		(fp_line
			(start -0.7874 0.4064)
			(end -0.7874 -0.4064)
			(stroke
				(width 0.1524)
				(type default)
			)
			(layer "F.SilkS")
		)
		(fp_line
			(start 0.7874 0.4064)
			(end -0.7874 0.4064)
			(stroke
				(width 0.1524)
				(type default)
			)
			(layer "F.SilkS")
		)
		(fp_line
			(start -0.7874 -0.4064)
			(end 0.7874 -0.4064)
			(stroke
				(width 0.1524)
				(type default)
			)
			(layer "F.SilkS")
		)
		(fp_line
			(start 0.7874 -0.4064)
			(end 0.7874 0.4064)
			(stroke
				(width 0.1524)
				(type default)
			)
			(layer "F.SilkS")
		)
		(fp_line
			(start -0.67945 0.3048)
			(end -0.67945 -0.305054)
			(stroke
				(width 0.1)
				(type default)
			)
			(layer "F.Fab")
		)
		(fp_line
			(start -0.12065 0.3048)
			(end -0.67945 0.3048)
			(stroke
				(width 0.1)
				(type default)
			)
			(layer "F.Fab")
		)
		(fp_line
			(start 0.120396 0.3048)
			(end 0.120396 0.2794)
			(stroke
				(width 0.1)
				(type default)
			)
			(layer "F.Fab")
		)
		(fp_line
			(start 0.67945 0.3048)
			(end 0.120396 0.3048)
			(stroke
				(width 0.1)
				(type default)
			)
			(layer "F.Fab")
		)
		(fp_line
			(start -0.12065 0.2794)
			(end -0.12065 0.3048)
			(stroke
				(width 0.1)
				(type default)
			)
			(layer "F.Fab")
		)
		(fp_line
			(start 0.120396 0.2794)
			(end -0.12065 0.2794)
			(stroke
				(width 0.1)
				(type default)
			)
			(layer "F.Fab")
		)
		(fp_line
			(start -0.12065 -0.2794)
			(end 0.12065 -0.2794)
			(stroke
				(width 0.1)
				(type default)
			)
			(layer "F.Fab")
		)
		(fp_line
			(start 0.12065 -0.2794)
			(end 0.12065 -0.3048)
			(stroke
				(width 0.1)
				(type default)
			)
			(layer "F.Fab")
		)
		(fp_line
			(start 0.12065 -0.3048)
			(end 0.67945 -0.3048)
			(stroke
				(width 0.1)
				(type default)
			)
			(layer "F.Fab")
		)
		(fp_line
			(start 0.67945 -0.3048)
			(end 0.67945 0.3048)
			(stroke
				(width 0.1)
				(type default)
			)
			(layer "F.Fab")
		)
		(fp_line
			(start -0.67945 -0.305054)
			(end -0.12065 -0.305054)
			(stroke
				(width 0.1)
				(type default)
			)
			(layer "F.Fab")
		)
		(fp_line
			(start -0.12065 -0.305054)
			(end -0.12065 -0.2794)
			(stroke
				(width 0.1)
				(type default)
			)
			(layer "F.Fab")
		)
		(pad "1" smd circle
			(at -0.40005 0 270)
			(size 0 0)
			(layers "F.Cu" "F.Mask" "F.Paste")
			(net "P3V3_AUX")
		)
		(pad "2" smd circle
			(at 0.40005 0 270)
			(size 0 0)
			(layers "F.Cu" "F.Mask" "F.Paste")
			(net "FM_CPU1_PKGID1")
		)
	)
	(footprint ""
		(layer "F.Cu")
		(at 437.93537 -174.805594)
		(property "Reference" "PR4683"
			(at 0 0 0)
			(layer "F.SilkS")
			(hide yes)
			(effects
				(font
					(size 1.27 1.27)
				)
			)
		)
		(property "Value" ""
			(at 0 0 0)
			(layer "F.Fab")
			(effects
				(font
					(size 1.27 1.27)
				)
			)
		)
		(duplicate_pad_numbers_are_jumpers no)
		(fp_line
			(start -0.7874 -0.4064)
			(end 0.7874 -0.4064)
			(stroke
				(width 0.1524)
				(type default)
			)
			(layer "F.SilkS")
		)
		(fp_line
			(start -0.7874 0.4064)
			(end -0.7874 -0.4064)
			(stroke
				(width 0.1524)
				(type default)
			)
			(layer "F.SilkS")
		)
		(fp_line
			(start 0.7874 -0.4064)
			(end 0.7874 0.4064)
			(stroke
				(width 0.1524)
				(type default)
			)
			(layer "F.SilkS")
		)
		(fp_line
			(start 0.7874 0.4064)
			(end -0.7874 0.4064)
			(stroke
				(width 0.1524)
				(type default)
			)
			(layer "F.SilkS")
		)
		(fp_line
			(start -0.67945 -0.305054)
			(end -0.12065 -0.305054)
			(stroke
				(width 0.1)
				(type default)
			)
			(layer "F.Fab")
		)
		(fp_line
			(start -0.67945 0.3048)
			(end -0.67945 -0.305054)
			(stroke
				(width 0.1)
				(type default)
			)
			(layer "F.Fab")
		)
		(fp_line
			(start -0.12065 -0.305054)
			(end -0.12065 -0.2794)
			(stroke
				(width 0.1)
				(type default)
			)
			(layer "F.Fab")
		)
		(fp_line
			(start -0.12065 -0.2794)
			(end 0.12065 -0.2794)
			(stroke
				(width 0.1)
				(type default)
			)
			(layer "F.Fab")
		)
		(fp_line
			(start -0.12065 0.2794)
			(end -0.12065 0.3048)
			(stroke
				(width 0.1)
				(type default)
			)
			(layer "F.Fab")
		)
		(fp_line
			(start -0.12065 0.3048)
			(end -0.67945 0.3048)
			(stroke
				(width 0.1)
				(type default)
			)
			(layer "F.Fab")
		)
		(fp_line
			(start 0.120396 0.2794)
			(end -0.12065 0.2794)
			(stroke
				(width 0.1)
				(type default)
			)
			(layer "F.Fab")
		)
		(fp_line
			(start 0.120396 0.3048)
			(end 0.120396 0.2794)
			(stroke
				(width 0.1)
				(type default)
			)
			(layer "F.Fab")
		)
		(fp_line
			(start 0.12065 -0.3048)
			(end 0.67945 -0.3048)
			(stroke
				(width 0.1)
				(type default)
			)
			(layer "F.Fab")
		)
		(fp_line
			(start 0.12065 -0.2794)
			(end 0.12065 -0.3048)
			(stroke
				(width 0.1)
				(type default)
			)
			(layer "F.Fab")
		)
		(fp_line
			(start 0.67945 -0.3048)
			(end 0.67945 0.3048)
			(stroke
				(width 0.1)
				(type default)
			)
			(layer "F.Fab")
		)
		(fp_line
			(start 0.67945 0.3048)
			(end 0.120396 0.3048)
			(stroke
				(width 0.1)
				(type default)
			)
			(layer "F.Fab")
		)
		(pad "1" smd circle
			(at -0.40005 0)
			(size 0 0)
			(layers "F.Cu" "F.Mask" "F.Paste")
			(net "PVNN_MAIN_CPU0_FB_RC")
		)
		(pad "2" smd circle
			(at 0.40005 0)
			(size 0 0)
			(layers "F.Cu" "F.Mask" "F.Paste")
			(net "PVNN_MAIN_CPU0")
		)
	)
	(footprint ""
		(layer "F.Cu")
		(at 25.632156 -180.529738 90)
		(property "Reference" "PC1283"
			(at 0 0 90)
			(layer "F.SilkS")
			(hide yes)
			(effects
				(font
					(size 1.27 1.27)
				)
			)
		)
		(property "Value" ""
			(at 0 0 90)
			(layer "F.Fab")
			(effects
				(font
					(size 1.27 1.27)
				)
			)
		)
		(duplicate_pad_numbers_are_jumpers no)
		(fp_line
			(start 0.7874 -0.4064)
			(end 0.7874 0.4064)
			(stroke
				(width 0.1524)
				(type default)
			)
			(layer "F.SilkS")
		)
		(fp_line
			(start -0.7874 -0.4064)
			(end 0.7874 -0.4064)
			(stroke
				(width 0.1524)
				(type default)
			)
			(layer "F.SilkS")
		)
		(fp_line
			(start 0.7874 0.4064)
			(end -0.7874 0.4064)
			(stroke
				(width 0.1524)
				(type default)
			)
			(layer "F.SilkS")
		)
		(fp_line
			(start -0.7874 0.4064)
			(end -0.7874 -0.4064)
			(stroke
				(width 0.1524)
				(type default)
			)
			(layer "F.SilkS")
		)
		(fp_line
			(start -0.12065 -0.305054)
			(end -0.12065 -0.2794)
			(stroke
				(width 0.1)
				(type default)
			)
			(layer "F.Fab")
		)
		(fp_line
			(start -0.67945 -0.305054)
			(end -0.12065 -0.305054)
			(stroke
				(width 0.1)
				(type default)
			)
			(layer "F.Fab")
		)
		(fp_line
			(start 0.67945 -0.3048)
			(end 0.67945 0.3048)
			(stroke
				(width 0.1)
				(type default)
			)
			(layer "F.Fab")
		)
		(fp_line
			(start 0.12065 -0.3048)
			(end 0.67945 -0.3048)
			(stroke
				(width 0.1)
				(type default)
			)
			(layer "F.Fab")
		)
		(fp_line
			(start 0.12065 -0.2794)
			(end 0.12065 -0.3048)
			(stroke
				(width 0.1)
				(type default)
			)
			(layer "F.Fab")
		)
		(fp_line
			(start -0.12065 -0.2794)
			(end 0.12065 -0.2794)
			(stroke
				(width 0.1)
				(type default)
			)
			(layer "F.Fab")
		)
		(fp_line
			(start 0.120396 0.2794)
			(end -0.12065 0.2794)
			(stroke
				(width 0.1)
				(type default)
			)
			(layer "F.Fab")
		)
		(fp_line
			(start -0.12065 0.2794)
			(end -0.12065 0.3048)
			(stroke
				(width 0.1)
				(type default)
			)
			(layer "F.Fab")
		)
		(fp_line
			(start 0.67945 0.3048)
			(end 0.120396 0.3048)
			(stroke
				(width 0.1)
				(type default)
			)
			(layer "F.Fab")
		)
		(fp_line
			(start 0.120396 0.3048)
			(end 0.120396 0.2794)
			(stroke
				(width 0.1)
				(type default)
			)
			(layer "F.Fab")
		)
		(fp_line
			(start -0.12065 0.3048)
			(end -0.67945 0.3048)
			(stroke
				(width 0.1)
				(type default)
			)
			(layer "F.Fab")
		)
		(fp_line
			(start -0.67945 0.3048)
			(end -0.67945 -0.305054)
			(stroke
				(width 0.1)
				(type default)
			)
			(layer "F.Fab")
		)
		(pad "1" smd circle
			(at -0.40005 0 90)
			(size 0 0)
			(layers "F.Cu" "F.Mask" "F.Paste")
			(net "SW_PVNN_MAIN_CPU1_BST_R")
		)
		(pad "2" smd circle
			(at 0.40005 0 90)
			(size 0 0)
			(layers "F.Cu" "F.Mask" "F.Paste")
			(net "SW_PVNN_MAIN_CPU1_SW")
		)
	)
)
